# TIMECARD (Time Appliance Project (Time Card)) — schematic netlist excerpt (pin names and nets, part order shuffled) for the footprints in the layout excerpt that follows; sources: Cadence DE-HDL packaged netlist, KiCad conversion of R4006-B0001-02_R01.brd

R198  RESISTOR  100OHM 1%  pkg SMC_0402R_H016  page 10 : \1\ = PCIE_REFCLKP ; \2\ = PCIE_REFCLKN
R45  RESISTOR  33OHM 1%  pkg SMC_0402R_H016  page 16 : \1\ = EEPROM_SDA ; \2\ = SEC_EEPROM_SDA

(kicad_pcb
	(version 20260206)
	(generator "pcbnew")
	(generator_version "10.0")
	(general
		(thickness 1.6)
		(legacy_teardrops no)
	)
	(paper "A4")
	(title_block
		(title "timecard-production-celestica-r4006 — R4006-B0001-02_R01.brd")
		(comment 1 "Time Appliance Project (Time Card) / footprints 756-757 of 1113")
	)
	(layers
		(0 "F.Cu" signal "TOP")
		(4 "In1.Cu" signal "L02_GND1")
		(6 "In2.Cu" signal "L03_SIG1")
		(8 "In3.Cu" signal "L04_GND2")
		(10 "In4.Cu" signal "L05_VCC1")
		(12 "In5.Cu" signal "L06_VCC2")
		(14 "In6.Cu" signal "L07_GND3")
		(16 "In7.Cu" signal "L08_SIG2")
		(18 "In8.Cu" signal "L09_GND4")
		(2 "B.Cu" signal "BOTTOM")
		(9 "F.Adhes" user "F.Adhesive")
		(11 "B.Adhes" user "B.Adhesive")
		(13 "F.Paste" user "Package Geometry/Pastemask Top")
		(15 "B.Paste" user "Package Geometry/Pastemask Bottom")
		(5 "F.SilkS" user "Ref Des/Silkscreen Top")
		(7 "B.SilkS" user "Ref Des/Silkscreen Bottom")
		(1 "F.Mask" user "Board Geometry/Soldermask Top")
		(3 "B.Mask" user "Board Geometry/Soldermask Bottom")
		(17 "Dwgs.User" user "User.Drawings")
		(19 "Cmts.User" user "User.Comments")
		(21 "Eco1.User" user "User.Eco1")
		(23 "Eco2.User" user "User.Eco2")
		(25 "Edge.Cuts" user "Board Geometry/Outline")
		(27 "Margin" user)
		(31 "F.CrtYd" user "Package Geometry/Place Bound Top")
		(29 "B.CrtYd" user "Package Geometry/Place Bound Bottom")
		(35 "F.Fab" user "Ref Des/Assembly Top")
		(33 "B.Fab" user "Ref Des/Assembly Bottom")
	)
	(footprint ""
		(layer "B.Cu")
		(at 18.3134 -21.2852 90)
		(property "Reference" "R45"
			(at -0.0762 -1.08077 270)
			(unlocked yes)
			(layer "B.SilkS")
			(effects
				(font
					(size 0.7874 0.5842)
					(thickness 0.1524)
				)
				(justify mirror)
			)
		)
		(property "Value" "VAL*"
			(at -0.02032 2.13233 90)
			(unlocked yes)
			(layer "B.Fab")
			(hide yes)
			(effects
				(font
					(size 0.7874 0.5842)
					(thickness 0.1524)
				)
				(justify mirror)
			)
		)
		(property "Tolerance" "TOL*"
			(at -0.044704 3.05435 90)
			(unlocked yes)
			(layer "Cmts.User")
			(hide yes)
			(effects
				(font
					(size 0.7874 0.5842)
					(thickness 0.1524)
				)
				(justify mirror)
			)
		)
		(property "User Part Number" "PARTNUM*"
			(at -0.02032 4.024884 90)
			(unlocked yes)
			(layer "Cmts.User")
			(hide yes)
			(effects
				(font
					(size 0.7874 0.5842)
					(thickness 0.1524)
				)
				(justify mirror)
			)
		)
		(property "Device Type" "RESISTOR-G155-133R0-01,33OHM,1%"
			(at -0.008382 1.210564 90)
			(unlocked yes)
			(layer "B.Fab")
			(hide yes)
			(effects
				(font
					(size 0.7874 0.5842)
					(thickness 0.1524)
				)
				(justify mirror)
			)
		)
		(duplicate_pad_numbers_are_jumpers no)
		(fp_line
			(start 1.143 -0.5588)
			(end 1.143 0.5588)
			(stroke
				(width 0.1)
				(type default)
			)
			(layer "B.SilkS")
		)
		(fp_line
			(start -1.143 -0.5588)
			(end 1.143 -0.5588)
			(stroke
				(width 0.1)
				(type default)
			)
			(layer "B.SilkS")
		)
		(fp_line
			(start 1.143 0.5588)
			(end -1.143 0.5588)
			(stroke
				(width 0.1)
				(type default)
			)
			(layer "B.SilkS")
		)
		(fp_line
			(start -1.143 0.5588)
			(end -1.143 -0.5588)
			(stroke
				(width 0.1)
				(type default)
			)
			(layer "B.SilkS")
		)
		(fp_rect
			(start 1.143 0.5588)
			(end -1.143 -0.5588)
			(stroke
				(width 0)
				(type default)
			)
			(fill no)
			(layer "B.CrtYd")
		)
		(fp_line
			(start 0.508 -0.3048)
			(end 0.508 0.3048)
			(stroke
				(width 0.1)
				(type default)
			)
			(layer "B.Fab")
		)
		(fp_line
			(start -0.508 -0.3048)
			(end 0.508 -0.3048)
			(stroke
				(width 0.1)
				(type default)
			)
			(layer "B.Fab")
		)
		(fp_line
			(start 0.508 0.3048)
			(end -0.508 0.3048)
			(stroke
				(width 0.1)
				(type default)
			)
			(layer "B.Fab")
		)
		(fp_line
			(start -0.508 0.3048)
			(end -0.508 -0.3048)
			(stroke
				(width 0.1)
				(type default)
			)
			(layer "B.Fab")
		)
		(pad "1" smd rect
			(at 0.5334 0 270)
			(size 0.7112 0.6096)
			(layers "B.Cu" "B.Mask" "B.Paste")
			(net "EEPROM_SDA")
		)
		(pad "2" smd rect
			(at -0.5334 0 270)
			(size 0.7112 0.6096)
			(layers "B.Cu" "B.Mask" "B.Paste")
			(net "SEC_EEPROM_SDA")
		)
		(zone
			(layer "B.Cu")
			(hatch none 0.5)
			(connect_pads
				(clearance 0)
			)
			(min_thickness 0.25)
			(keepout
				(tracks allowed)
				(vias not_allowed)
				(pads allowed)
				(copperpour not_allowed)
				(footprints allowed)
			)
			(placement
				(enabled no)
				(sheetname "")
			)
			(fill
				(thermal_gap 0.5)
				(thermal_bridge_width 0.5)
				(island_removal_mode 0)
			)
			(polygon
				(pts
					(xy 18.6182 -21.3614) (xy 18.0086 -21.3614) (xy 18.0086 -21.209) (xy 18.6182 -21.209)
				)
			)
		)
	)
	(footprint ""
		(layer "B.Cu")
		(at 103.347012 -42.82313)
		(property "Reference" "R198"
			(at -41.625012 0.94488 0)
			(unlocked yes)
			(layer "B.SilkS")
			(effects
				(font
					(size 0.635 0.4064)
					(thickness 0.1524)
				)
				(justify mirror)
			)
		)
		(property "Value" "VAL*"
			(at 0 3.718306 0)
			(unlocked yes)
			(layer "B.Fab")
			(hide yes)
			(effects
				(font
					(size 0.7874 0.5842)
					(thickness 0.127)
				)
				(justify mirror)
			)
		)
		(property "Device Type" "RESISTOR-G155-11000-01,100OHM,A"
			(at 0 1.432306 0)
			(unlocked yes)
			(layer "B.Fab")
			(hide yes)
			(effects
				(font
					(size 0.7874 0.5842)
					(thickness 0.127)
				)
				(justify mirror)
			)
		)
		(property "User Part Number" "PARTNUM*"
			(at 0 2.575306 0)
			(unlocked yes)
			(layer "Cmts.User")
			(hide yes)
			(effects
				(font
					(size 0.7874 0.5842)
					(thickness 0.127)
				)
				(justify mirror)
			)
		)
		(property "Tolerance" "TOL*"
			(at 0 4.861306 0)
			(unlocked yes)
			(layer "Cmts.User")
			(hide yes)
			(effects
				(font
					(size 0.7874 0.5842)
					(thickness 0.127)
				)
				(justify mirror)
			)
		)
		(duplicate_pad_numbers_are_jumpers no)
		(fp_line
			(start -0.970026 -0.4699)
			(end -0.970026 0.4699)
			(stroke
				(width 0.1)
				(type default)
			)
			(layer "B.SilkS")
		)
		(fp_line
			(start -0.970026 0.4699)
			(end 0.970026 0.4699)
			(stroke
				(width 0.1)
				(type default)
			)
			(layer "B.SilkS")
		)
		(fp_line
			(start 0.970026 -0.4699)
			(end -0.970026 -0.4699)
			(stroke
				(width 0.1)
				(type default)
			)
			(layer "B.SilkS")
		)
		(fp_line
			(start 0.970026 0.4699)
			(end 0.970026 -0.4699)
			(stroke
				(width 0.1)
				(type default)
			)
			(layer "B.SilkS")
		)
		(fp_poly
			(pts
				(xy 0.970026 0.4699) (xy -0.970026 0.4699) (xy -0.970026 -0.4699) (xy 0.970026 -0.4699)
			)
			(stroke
				(width 0)
				(type default)
			)
			(fill no)
			(layer "B.CrtYd")
		)
		(fp_line
			(start -0.508 -0.3048)
			(end -0.508 0.3048)
			(stroke
				(width 0.1)
				(type default)
			)
			(layer "B.Fab")
		)
		(fp_line
			(start -0.508 0.3048)
			(end 0.508 0.3048)
			(stroke
				(width 0.1)
				(type default)
			)
			(layer "B.Fab")
		)
		(fp_line
			(start 0.508 -0.3048)
			(end -0.508 -0.3048)
			(stroke
				(width 0.1)
				(type default)
			)
			(layer "B.Fab")
		)
		(fp_line
			(start 0.508 0.3048)
			(end 0.508 -0.3048)
			(stroke
				(width 0.1)
				(type default)
			)
			(layer "B.Fab")
		)
		(pad "1" smd circle
			(at 0.500126 0 180)
			(size 0.635 0.635)
			(layers "B.Cu" "B.Mask" "B.Paste")
			(net "PCIE_REFCLKP")
		)
		(pad "2" smd circle
			(at -0.500126 0 180)
			(size 0.635 0.635)
			(layers "B.Cu" "B.Mask" "B.Paste")
			(net "PCIE_REFCLKN")
		)
	)
)
